(kicad_pcb
	(version 20260206)
	(generator "pcbnew")
	(generator_version "10.0")
	(general
		(thickness 1.6)
		(legacy_teardrops no)
	)
	(paper "A4")
	(title_block
		(title "12092022_DA0F0TMDCD0_F0T_Management_Board_D_brd_V3_OCP.brd")
		(comment 1 "Grand Teton / footprints 660-665 of 1440")
	)
	(layers
		(0 "F.Cu" signal "TOP")
		(4 "In1.Cu" signal "GND")
		(6 "In2.Cu" signal "IN1")
		(8 "In3.Cu" signal "GND1")
		(10 "In4.Cu" signal "IN2")
		(12 "In5.Cu" signal "VCC")
		(14 "In6.Cu" signal "VCC1")
		(16 "In7.Cu" signal "IN3")
		(18 "In8.Cu" signal "GND2")
		(20 "In9.Cu" signal "IN4")
		(22 "In10.Cu" signal "GND3")
		(2 "B.Cu" signal "BOTTOM")
		(9 "F.Adhes" user "F.Adhesive")
		(11 "B.Adhes" user "B.Adhesive")
		(13 "F.Paste" user "Package Geometry/Pastemask Top")
		(15 "B.Paste" user "Package Geometry/Pastemask Bottom")
		(5 "F.SilkS" user "Ref Des/Silkscreen Top")
		(7 "B.SilkS" user "Ref Des/Silkscreen Bottom")
		(1 "F.Mask" user "Board Geometry/Soldermask Top")
		(3 "B.Mask" user "Board Geometry/Soldermask Bottom")
		(17 "Dwgs.User" user "User.Drawings")
		(19 "Cmts.User" user "User.Comments")
		(21 "Eco1.User" user "User.Eco1")
		(23 "Eco2.User" user "User.Eco2")
		(25 "Edge.Cuts" user "Board Geometry/Outline")
		(27 "Margin" user)
		(31 "F.CrtYd" user "Package Geometry/Place Bound Top")
		(29 "B.CrtYd" user "Package Geometry/Place Bound Bottom")
		(35 "F.Fab" user "Ref Des/Assembly Top")
		(33 "B.Fab" user "Ref Des/Assembly Bottom")
	)
	(footprint ""
		(layer "F.Cu")
		(at 11.783568 -50.110898 -90)
		(property "Reference" "PR527"
			(at 0 0 270)
			(layer "F.SilkS")
			(hide yes)
			(effects
				(font
					(size 1.27 1.27)
				)
			)
		)
		(property "Value" ""
			(at 0 0 270)
			(layer "F.Fab")
			(effects
				(font
					(size 1.27 1.27)
				)
			)
		)
		(duplicate_pad_numbers_are_jumpers no)
		(fp_line
			(start -0.7874 0.4064)
			(end -0.7874 -0.4064)
			(stroke
				(width 0.1524)
				(type default)
			)
			(layer "F.SilkS")
		)
		(fp_line
			(start 0.7874 0.4064)
			(end -0.7874 0.4064)
			(stroke
				(width 0.1524)
				(type default)
			)
			(layer "F.SilkS")
		)
		(fp_line
			(start -0.7874 -0.4064)
			(end 0.7874 -0.4064)
			(stroke
				(width 0.1524)
				(type default)
			)
			(layer "F.SilkS")
		)
		(fp_line
			(start 0.7874 -0.4064)
			(end 0.7874 0.4064)
			(stroke
				(width 0.1524)
				(type default)
			)
			(layer "F.SilkS")
		)
		(fp_line
			(start -0.67945 0.3048)
			(end -0.67945 -0.305054)
			(stroke
				(width 0.1)
				(type default)
			)
			(layer "F.Fab")
		)
		(fp_line
			(start -0.12065 0.3048)
			(end -0.67945 0.3048)
			(stroke
				(width 0.1)
				(type default)
			)
			(layer "F.Fab")
		)
		(fp_line
			(start 0.120396 0.3048)
			(end 0.120396 0.2794)
			(stroke
				(width 0.1)
				(type default)
			)
			(layer "F.Fab")
		)
		(fp_line
			(start 0.67945 0.3048)
			(end 0.120396 0.3048)
			(stroke
				(width 0.1)
				(type default)
			)
			(layer "F.Fab")
		)
		(fp_line
			(start -0.12065 0.2794)
			(end -0.12065 0.3048)
			(stroke
				(width 0.1)
				(type default)
			)
			(layer "F.Fab")
		)
		(fp_line
			(start 0.120396 0.2794)
			(end -0.12065 0.2794)
			(stroke
				(width 0.1)
				(type default)
			)
			(layer "F.Fab")
		)
		(fp_line
			(start -0.12065 -0.2794)
			(end 0.12065 -0.2794)
			(stroke
				(width 0.1)
				(type default)
			)
			(layer "F.Fab")
		)
		(fp_line
			(start 0.12065 -0.2794)
			(end 0.12065 -0.3048)
			(stroke
				(width 0.1)
				(type default)
			)
			(layer "F.Fab")
		)
		(fp_line
			(start 0.12065 -0.3048)
			(end 0.67945 -0.3048)
			(stroke
				(width 0.1)
				(type default)
			)
			(layer "F.Fab")
		)
		(fp_line
			(start 0.67945 -0.3048)
			(end 0.67945 0.3048)
			(stroke
				(width 0.1)
				(type default)
			)
			(layer "F.Fab")
		)
		(fp_line
			(start -0.67945 -0.305054)
			(end -0.12065 -0.305054)
			(stroke
				(width 0.1)
				(type default)
			)
			(layer "F.Fab")
		)
		(fp_line
			(start -0.12065 -0.305054)
			(end -0.12065 -0.2794)
			(stroke
				(width 0.1)
				(type default)
			)
			(layer "F.Fab")
		)
		(pad "1" smd circle
			(at -0.40005 0 270)
			(size 0 0)
			(layers "F.Cu" "F.Mask" "F.Paste")
			(net "P5V_AUX_FB")
		)
		(pad "2" smd circle
			(at 0.40005 0 270)
			(size 0 0)
			(layers "F.Cu" "F.Mask" "F.Paste")
			(net "P5V_AUX")
		)
	)
	(footprint ""
		(layer "F.Cu")
		(at 83.77555 -70.458838 -90)
		(property "Reference" "PR274"
			(at 0 0 270)
			(layer "F.SilkS")
			(hide yes)
			(effects
				(font
					(size 1.27 1.27)
				)
			)
		)
		(property "Value" ""
			(at 0 0 270)
			(layer "F.Fab")
			(effects
				(font
					(size 1.27 1.27)
				)
			)
		)
		(duplicate_pad_numbers_are_jumpers no)
		(fp_line
			(start -0.7874 0.4064)
			(end -0.7874 -0.4064)
			(stroke
				(width 0.1524)
				(type default)
			)
			(layer "F.SilkS")
		)
		(fp_line
			(start 0.7874 0.4064)
			(end -0.7874 0.4064)
			(stroke
				(width 0.1524)
				(type default)
			)
			(layer "F.SilkS")
		)
		(fp_line
			(start -0.7874 -0.4064)
			(end 0.7874 -0.4064)
			(stroke
				(width 0.1524)
				(type default)
			)
			(layer "F.SilkS")
		)
		(fp_line
			(start 0.7874 -0.4064)
			(end 0.7874 0.4064)
			(stroke
				(width 0.1524)
				(type default)
			)
			(layer "F.SilkS")
		)
		(fp_line
			(start -0.67945 0.3048)
			(end -0.67945 -0.305054)
			(stroke
				(width 0.1)
				(type default)
			)
			(layer "F.Fab")
		)
		(fp_line
			(start -0.12065 0.3048)
			(end -0.67945 0.3048)
			(stroke
				(width 0.1)
				(type default)
			)
			(layer "F.Fab")
		)
		(fp_line
			(start 0.120396 0.3048)
			(end 0.120396 0.2794)
			(stroke
				(width 0.1)
				(type default)
			)
			(layer "F.Fab")
		)
		(fp_line
			(start 0.67945 0.3048)
			(end 0.120396 0.3048)
			(stroke
				(width 0.1)
				(type default)
			)
			(layer "F.Fab")
		)
		(fp_line
			(start -0.12065 0.2794)
			(end -0.12065 0.3048)
			(stroke
				(width 0.1)
				(type default)
			)
			(layer "F.Fab")
		)
		(fp_line
			(start 0.120396 0.2794)
			(end -0.12065 0.2794)
			(stroke
				(width 0.1)
				(type default)
			)
			(layer "F.Fab")
		)
		(fp_line
			(start -0.12065 -0.2794)
			(end 0.12065 -0.2794)
			(stroke
				(width 0.1)
				(type default)
			)
			(layer "F.Fab")
		)
		(fp_line
			(start 0.12065 -0.2794)
			(end 0.12065 -0.3048)
			(stroke
				(width 0.1)
				(type default)
			)
			(layer "F.Fab")
		)
		(fp_line
			(start 0.12065 -0.3048)
			(end 0.67945 -0.3048)
			(stroke
				(width 0.1)
				(type default)
			)
			(layer "F.Fab")
		)
		(fp_line
			(start 0.67945 -0.3048)
			(end 0.67945 0.3048)
			(stroke
				(width 0.1)
				(type default)
			)
			(layer "F.Fab")
		)
		(fp_line
			(start -0.67945 -0.305054)
			(end -0.12065 -0.305054)
			(stroke
				(width 0.1)
				(type default)
			)
			(layer "F.Fab")
		)
		(fp_line
			(start -0.12065 -0.305054)
			(end -0.12065 -0.2794)
			(stroke
				(width 0.1)
				(type default)
			)
			(layer "F.Fab")
		)
		(pad "1" smd circle
			(at -0.40005 0 270)
			(size 0 0)
			(layers "F.Cu" "F.Mask" "F.Paste")
			(net "P3V3_AUX")
		)
		(pad "2" smd circle
			(at 0.40005 0 270)
			(size 0 0)
			(layers "F.Cu" "F.Mask" "F.Paste")
			(net "PVCC1_AUX")
		)
	)
	(footprint ""
		(layer "F.Cu")
		(at 10.287 -91.059 -90)
		(property "Reference" "R514"
			(at 0 0 270)
			(layer "F.SilkS")
			(hide yes)
			(effects
				(font
					(size 1.27 1.27)
				)
			)
		)
		(property "Value" ""
			(at 0 0 270)
			(layer "F.Fab")
			(effects
				(font
					(size 1.27 1.27)
				)
			)
		)
		(duplicate_pad_numbers_are_jumpers no)
		(fp_line
			(start -0.7874 0.4064)
			(end -0.7874 -0.4064)
			(stroke
				(width 0.1524)
				(type default)
			)
			(layer "F.SilkS")
		)
		(fp_line
			(start 0.7874 0.4064)
			(end -0.7874 0.4064)
			(stroke
				(width 0.1524)
				(type default)
			)
			(layer "F.SilkS")
		)
		(fp_line
			(start -0.7874 -0.4064)
			(end 0.7874 -0.4064)
			(stroke
				(width 0.1524)
				(type default)
			)
			(layer "F.SilkS")
		)
		(fp_line
			(start 0.7874 -0.4064)
			(end 0.7874 0.4064)
			(stroke
				(width 0.1524)
				(type default)
			)
			(layer "F.SilkS")
		)
		(fp_line
			(start -0.67945 0.3048)
			(end -0.67945 -0.305054)
			(stroke
				(width 0.1)
				(type default)
			)
			(layer "F.Fab")
		)
		(fp_line
			(start -0.12065 0.3048)
			(end -0.67945 0.3048)
			(stroke
				(width 0.1)
				(type default)
			)
			(layer "F.Fab")
		)
		(fp_line
			(start 0.120396 0.3048)
			(end 0.120396 0.2794)
			(stroke
				(width 0.1)
				(type default)
			)
			(layer "F.Fab")
		)
		(fp_line
			(start 0.67945 0.3048)
			(end 0.120396 0.3048)
			(stroke
				(width 0.1)
				(type default)
			)
			(layer "F.Fab")
		)
		(fp_line
			(start -0.12065 0.2794)
			(end -0.12065 0.3048)
			(stroke
				(width 0.1)
				(type default)
			)
			(layer "F.Fab")
		)
		(fp_line
			(start 0.120396 0.2794)
			(end -0.12065 0.2794)
			(stroke
				(width 0.1)
				(type default)
			)
			(layer "F.Fab")
		)
		(fp_line
			(start -0.12065 -0.2794)
			(end 0.12065 -0.2794)
			(stroke
				(width 0.1)
				(type default)
			)
			(layer "F.Fab")
		)
		(fp_line
			(start 0.12065 -0.2794)
			(end 0.12065 -0.3048)
			(stroke
				(width 0.1)
				(type default)
			)
			(layer "F.Fab")
		)
		(fp_line
			(start 0.12065 -0.3048)
			(end 0.67945 -0.3048)
			(stroke
				(width 0.1)
				(type default)
			)
			(layer "F.Fab")
		)
		(fp_line
			(start 0.67945 -0.3048)
			(end 0.67945 0.3048)
			(stroke
				(width 0.1)
				(type default)
			)
			(layer "F.Fab")
		)
		(fp_line
			(start -0.67945 -0.305054)
			(end -0.12065 -0.305054)
			(stroke
				(width 0.1)
				(type default)
			)
			(layer "F.Fab")
		)
		(fp_line
			(start -0.12065 -0.305054)
			(end -0.12065 -0.2794)
			(stroke
				(width 0.1)
				(type default)
			)
			(layer "F.Fab")
		)
		(pad "1" smd circle
			(at -0.40005 0 270)
			(size 0 0)
			(layers "F.Cu" "F.Mask" "F.Paste")
			(net "JTAG_SCM_PLD_TCK")
		)
		(pad "2" smd circle
			(at 0.40005 0 270)
			(size 0 0)
			(layers "F.Cu" "F.Mask" "F.Paste")
			(net "JTAG_SCM_CONN_TCK")
		)
	)
	(footprint ""
		(layer "F.Cu")
		(at 43.848528 -30.867604 90)
		(property "Reference" "R62"
			(at 0 0 90)
			(layer "F.SilkS")
			(hide yes)
			(effects
				(font
					(size 1.27 1.27)
				)
			)
		)
		(property "Value" ""
			(at 0 0 90)
			(layer "F.Fab")
			(effects
				(font
					(size 1.27 1.27)
				)
			)
		)
		(duplicate_pad_numbers_are_jumpers no)
		(fp_line
			(start 0.7874 -0.4064)
			(end 0.7874 0.4064)
			(stroke
				(width 0.1524)
				(type default)
			)
			(layer "F.SilkS")
		)
		(fp_line
			(start -0.7874 -0.4064)
			(end 0.7874 -0.4064)
			(stroke
				(width 0.1524)
				(type default)
			)
			(layer "F.SilkS")
		)
		(fp_line
			(start 0.7874 0.4064)
			(end -0.7874 0.4064)
			(stroke
				(width 0.1524)
				(type default)
			)
			(layer "F.SilkS")
		)
		(fp_line
			(start -0.7874 0.4064)
			(end -0.7874 -0.4064)
			(stroke
				(width 0.1524)
				(type default)
			)
			(layer "F.SilkS")
		)
		(fp_line
			(start -0.12065 -0.305054)
			(end -0.12065 -0.2794)
			(stroke
				(width 0.1)
				(type default)
			)
			(layer "F.Fab")
		)
		(fp_line
			(start -0.67945 -0.305054)
			(end -0.12065 -0.305054)
			(stroke
				(width 0.1)
				(type default)
			)
			(layer "F.Fab")
		)
		(fp_line
			(start 0.67945 -0.3048)
			(end 0.67945 0.3048)
			(stroke
				(width 0.1)
				(type default)
			)
			(layer "F.Fab")
		)
		(fp_line
			(start 0.12065 -0.3048)
			(end 0.67945 -0.3048)
			(stroke
				(width 0.1)
				(type default)
			)
			(layer "F.Fab")
		)
		(fp_line
			(start 0.12065 -0.2794)
			(end 0.12065 -0.3048)
			(stroke
				(width 0.1)
				(type default)
			)
			(layer "F.Fab")
		)
		(fp_line
			(start -0.12065 -0.2794)
			(end 0.12065 -0.2794)
			(stroke
				(width 0.1)
				(type default)
			)
			(layer "F.Fab")
		)
		(fp_line
			(start 0.120396 0.2794)
			(end -0.12065 0.2794)
			(stroke
				(width 0.1)
				(type default)
			)
			(layer "F.Fab")
		)
		(fp_line
			(start -0.12065 0.2794)
			(end -0.12065 0.3048)
			(stroke
				(width 0.1)
				(type default)
			)
			(layer "F.Fab")
		)
		(fp_line
			(start 0.67945 0.3048)
			(end 0.120396 0.3048)
			(stroke
				(width 0.1)
				(type default)
			)
			(layer "F.Fab")
		)
		(fp_line
			(start 0.120396 0.3048)
			(end 0.120396 0.2794)
			(stroke
				(width 0.1)
				(type default)
			)
			(layer "F.Fab")
		)
		(fp_line
			(start -0.12065 0.3048)
			(end -0.67945 0.3048)
			(stroke
				(width 0.1)
				(type default)
			)
			(layer "F.Fab")
		)
		(fp_line
			(start -0.67945 0.3048)
			(end -0.67945 -0.305054)
			(stroke
				(width 0.1)
				(type default)
			)
			(layer "F.Fab")
		)
		(pad "1" smd circle
			(at -0.40005 0 90)
			(size 0 0)
			(layers "F.Cu" "F.Mask" "F.Paste")
			(net "P3V3_AUX")
		)
		(pad "2" smd circle
			(at 0.40005 0 90)
			(size 0 0)
			(layers "F.Cu" "F.Mask" "F.Paste")
			(net "FM_PCH_BMC_THERMTRIP_N")
		)
	)
	(footprint ""
		(layer "F.Cu")
		(at 46.863 -22.352 180)
		(property "Reference" "R378"
			(at 0 0 180)
			(layer "F.SilkS")
			(hide yes)
			(effects
				(font
					(size 1.27 1.27)
				)
			)
		)
		(property "Value" ""
			(at 0 0 180)
			(layer "F.Fab")
			(effects
				(font
					(size 1.27 1.27)
				)
			)
		)
		(duplicate_pad_numbers_are_jumpers no)
		(fp_line
			(start 0.7874 0.4064)
			(end -0.7874 0.4064)
			(stroke
				(width 0.1524)
				(type default)
			)
			(layer "F.SilkS")
		)
		(fp_line
			(start 0.7874 -0.4064)
			(end 0.7874 0.4064)
			(stroke
				(width 0.1524)
				(type default)
			)
			(layer "F.SilkS")
		)
		(fp_line
			(start -0.7874 0.4064)
			(end -0.7874 -0.4064)
			(stroke
				(width 0.1524)
				(type default)
			)
			(layer "F.SilkS")
		)
		(fp_line
			(start -0.7874 -0.4064)
			(end 0.7874 -0.4064)
			(stroke
				(width 0.1524)
				(type default)
			)
			(layer "F.SilkS")
		)
		(fp_line
			(start 0.67945 0.3048)
			(end 0.120396 0.3048)
			(stroke
				(width 0.1)
				(type default)
			)
			(layer "F.Fab")
		)
		(fp_line
			(start 0.67945 -0.3048)
			(end 0.67945 0.3048)
			(stroke
				(width 0.1)
				(type default)
			)
			(layer "F.Fab")
		)
		(fp_line
			(start 0.12065 -0.2794)
			(end 0.12065 -0.3048)
			(stroke
				(width 0.1)
				(type default)
			)
			(layer "F.Fab")
		)
		(fp_line
			(start 0.12065 -0.3048)
			(end 0.67945 -0.3048)
			(stroke
				(width 0.1)
				(type default)
			)
			(layer "F.Fab")
		)
		(fp_line
			(start 0.120396 0.3048)
			(end 0.120396 0.2794)
			(stroke
				(width 0.1)
				(type default)
			)
			(layer "F.Fab")
		)
		(fp_line
			(start 0.120396 0.2794)
			(end -0.12065 0.2794)
			(stroke
				(width 0.1)
				(type default)
			)
			(layer "F.Fab")
		)
		(fp_line
			(start -0.12065 0.3048)
			(end -0.67945 0.3048)
			(stroke
				(width 0.1)
				(type default)
			)
			(layer "F.Fab")
		)
		(fp_line
			(start -0.12065 0.2794)
			(end -0.12065 0.3048)
			(stroke
				(width 0.1)
				(type default)
			)
			(layer "F.Fab")
		)
		(fp_line
			(start -0.12065 -0.2794)
			(end 0.12065 -0.2794)
			(stroke
				(width 0.1)
				(type default)
			)
			(layer "F.Fab")
		)
		(fp_line
			(start -0.12065 -0.305054)
			(end -0.12065 -0.2794)
			(stroke
				(width 0.1)
				(type default)
			)
			(layer "F.Fab")
		)
		(fp_line
			(start -0.67945 0.3048)
			(end -0.67945 -0.305054)
			(stroke
				(width 0.1)
				(type default)
			)
			(layer "F.Fab")
		)
		(fp_line
			(start -0.67945 -0.305054)
			(end -0.12065 -0.305054)
			(stroke
				(width 0.1)
				(type default)
			)
			(layer "F.Fab")
		)
		(pad "1" smd circle
			(at -0.40005 0 180)
			(size 0 0)
			(layers "F.Cu" "F.Mask" "F.Paste")
			(net "USB_OC0_ILIM")
		)
		(pad "2" smd circle
			(at 0.40005 0 180)
			(size 0 0)
			(layers "F.Cu" "F.Mask" "F.Paste")
			(net "GND")
		)
	)
	(footprint ""
		(layer "F.Cu")
		(at 12.319 -92.456 180)
		(property "Reference" "R595"
			(at 0 0 180)
			(layer "F.SilkS")
			(hide yes)
			(effects
				(font
					(size 1.27 1.27)
				)
			)
		)
		(property "Value" ""
			(at 0 0 180)
			(layer "F.Fab")
			(effects
				(font
					(size 1.27 1.27)
				)
			)
		)
		(duplicate_pad_numbers_are_jumpers no)
		(fp_line
			(start 0.7874 0.4064)
			(end -0.7874 0.4064)
			(stroke
				(width 0.1524)
				(type default)
			)
			(layer "F.SilkS")
		)
		(fp_line
			(start 0.7874 -0.4064)
			(end 0.7874 0.4064)
			(stroke
				(width 0.1524)
				(type default)
			)
			(layer "F.SilkS")
		)
		(fp_line
			(start -0.7874 0.4064)
			(end -0.7874 -0.4064)
			(stroke
				(width 0.1524)
				(type default)
			)
			(layer "F.SilkS")
		)
		(fp_line
			(start -0.7874 -0.4064)
			(end 0.7874 -0.4064)
			(stroke
				(width 0.1524)
				(type default)
			)
			(layer "F.SilkS")
		)
		(fp_line
			(start 0.67945 0.3048)
			(end 0.120396 0.3048)
			(stroke
				(width 0.1)
				(type default)
			)
			(layer "F.Fab")
		)
		(fp_line
			(start 0.67945 -0.3048)
			(end 0.67945 0.3048)
			(stroke
				(width 0.1)
				(type default)
			)
			(layer "F.Fab")
		)
		(fp_line
			(start 0.12065 -0.2794)
			(end 0.12065 -0.3048)
			(stroke
				(width 0.1)
				(type default)
			)
			(layer "F.Fab")
		)
		(fp_line
			(start 0.12065 -0.3048)
			(end 0.67945 -0.3048)
			(stroke
				(width 0.1)
				(type default)
			)
			(layer "F.Fab")
		)
		(fp_line
			(start 0.120396 0.3048)
			(end 0.120396 0.2794)
			(stroke
				(width 0.1)
				(type default)
			)
			(layer "F.Fab")
		)
		(fp_line
			(start 0.120396 0.2794)
			(end -0.12065 0.2794)
			(stroke
				(width 0.1)
				(type default)
			)
			(layer "F.Fab")
		)
		(fp_line
			(start -0.12065 0.3048)
			(end -0.67945 0.3048)
			(stroke
				(width 0.1)
				(type default)
			)
			(layer "F.Fab")
		)
		(fp_line
			(start -0.12065 0.2794)
			(end -0.12065 0.3048)
			(stroke
				(width 0.1)
				(type default)
			)
			(layer "F.Fab")
		)
		(fp_line
			(start -0.12065 -0.2794)
			(end 0.12065 -0.2794)
			(stroke
				(width 0.1)
				(type default)
			)
			(layer "F.Fab")
		)
		(fp_line
			(start -0.12065 -0.305054)
			(end -0.12065 -0.2794)
			(stroke
				(width 0.1)
				(type default)
			)
			(layer "F.Fab")
		)
		(fp_line
			(start -0.67945 0.3048)
			(end -0.67945 -0.305054)
			(stroke
				(width 0.1)
				(type default)
			)
			(layer "F.Fab")
		)
		(fp_line
			(start -0.67945 -0.305054)
			(end -0.12065 -0.305054)
			(stroke
				(width 0.1)
				(type default)
			)
			(layer "F.Fab")
		)
		(pad "1" smd circle
			(at -0.40005 0 180)
			(size 0 0)
			(layers "F.Cu" "F.Mask" "F.Paste")
			(net "P3V3_AUX")
		)
		(pad "2" smd circle
			(at 0.40005 0 180)
			(size 0 0)
			(layers "F.Cu" "F.Mask" "F.Paste")
			(net "BMC_CPLD_GPIO_8")
		)
	)
)
